(kicad_pcb
	(version 20260206)
	(generator "pcbnew")
	(generator_version "10.0")
	(general
		(thickness 1.6)
		(legacy_teardrops no)
	)
	(paper "A4")
	(title_block
		(title "panther-plus-userver — 13130-1b_20150205.brd")
		(comment 1 "Honey Badger (Wiwynn) / footprints 451-458 of 1509")
	)
	(layers
		(0 "F.Cu" signal "TOP")
		(4 "In1.Cu" signal "L2")
		(6 "In2.Cu" signal "L3")
		(8 "In3.Cu" signal "L4")
		(10 "In4.Cu" signal "L5")
		(12 "In5.Cu" signal "L6")
		(14 "In6.Cu" signal "L7")
		(16 "In7.Cu" signal "L8")
		(18 "In8.Cu" signal "L9")
		(20 "In9.Cu" signal "L10")
		(22 "In10.Cu" signal "L11")
		(2 "B.Cu" signal "BOTTOM")
		(9 "F.Adhes" user "F.Adhesive")
		(11 "B.Adhes" user "B.Adhesive")
		(13 "F.Paste" user "Package Geometry/Pastemask Top")
		(15 "B.Paste" user "Package Geometry/Pastemask Bottom")
		(5 "F.SilkS" user "Ref Des/Silkscreen Top")
		(7 "B.SilkS" user "Ref Des/Silkscreen Bottom")
		(1 "F.Mask" user "Board Geometry/Soldermask Top")
		(3 "B.Mask" user "Board Geometry/Soldermask Bottom")
		(17 "Dwgs.User" user "User.Drawings")
		(19 "Cmts.User" user "User.Comments")
		(21 "Eco1.User" user "User.Eco1")
		(23 "Eco2.User" user "User.Eco2")
		(25 "Edge.Cuts" user "Board Geometry/Outline")
		(27 "Margin" user)
		(31 "F.CrtYd" user "Package Geometry/Place Bound Top")
		(29 "B.CrtYd" user "Package Geometry/Place Bound Bottom")
		(35 "F.Fab" user "Ref Des/Assembly Top")
		(33 "B.Fab" user "Ref Des/Assembly Bottom")
	)
	(footprint ""
		(layer "F.Cu")
		(at 44.704 -20.701 -90)
		(property "Reference" "R247"
			(at 0 0 270)
			(layer "F.SilkS")
			(hide yes)
			(effects
				(font
					(size 1.27 1.27)
				)
			)
		)
		(property "Value" "51R2F-2-GP"
			(at 0.064008 -3.993896 270)
			(unlocked yes)
			(layer "F.Fab")
			(hide yes)
			(effects
				(font
					(size 1.016 1.016)
					(thickness 0.1524)
				)
			)
		)
		(property "Device Type" "R402H16"
			(at 0.064008 -5.517896 270)
			(unlocked yes)
			(layer "F.Fab")
			(hide yes)
			(effects
				(font
					(size 1.016 1.016)
					(thickness 0.1524)
				)
			)
		)
		(duplicate_pad_numbers_are_jumpers no)
		(fp_rect
			(start -0.381 0.8382)
			(end 0.381 -0.8382)
			(stroke
				(width 0)
				(type default)
			)
			(fill no)
			(layer "F.CrtYd")
		)
		(fp_rect
			(start -0.381 0.8382)
			(end 0.381 -0.8382)
			(stroke
				(width 0)
				(type default)
			)
			(fill no)
			(layer "F.Fab")
		)
		(pad "1" smd custom
			(at 0 -0.4318 270)
			(size 0.127 0.127)
			(layers "F.Cu" "F.Mask" "F.Paste")
			(net "P1V0")
			(options
				(clearance outline)
				(anchor circle)
			)
			(primitives
				(gr_poly
					(pts
						(arc
							(start -0.2032 -0.2794)
							(mid -0.239121 -0.264521)
							(end -0.254 -0.2286)
						)
						(arc
							(start -0.254 0.2286)
							(mid -0.239121 0.264521)
							(end -0.2032 0.2794)
						)
						(arc
							(start 0.2032 0.2794)
							(mid 0.239121 0.264521)
							(end 0.254 0.2286)
						)
						(arc
							(start 0.254 -0.2286)
							(mid 0.239121 -0.264521)
							(end 0.2032 -0.2794)
						)
					)
					(width 0)
					(fill yes)
				)
			)
		)
		(pad "2" smd custom
			(at 0 0.4318 270)
			(size 0.127 0.127)
			(layers "F.Cu" "F.Mask" "F.Paste")
			(net "XDP_CPU_PREQ#")
			(options
				(clearance outline)
				(anchor circle)
			)
			(primitives
				(gr_poly
					(pts
						(arc
							(start -0.2032 -0.2794)
							(mid -0.239121 -0.264521)
							(end -0.254 -0.2286)
						)
						(arc
							(start -0.254 0.2286)
							(mid -0.239121 0.264521)
							(end -0.2032 0.2794)
						)
						(arc
							(start 0.2032 0.2794)
							(mid 0.239121 0.264521)
							(end 0.254 0.2286)
						)
						(arc
							(start 0.254 -0.2286)
							(mid 0.239121 -0.264521)
							(end 0.2032 -0.2794)
						)
					)
					(width 0)
					(fill yes)
				)
			)
		)
	)
	(footprint ""
		(layer "F.Cu")
		(at 197.739 -3.048 90)
		(property "Reference" "C90"
			(at 0 0 90)
			(layer "F.SilkS")
			(hide yes)
			(effects
				(font
					(size 1.27 1.27)
				)
			)
		)
		(property "Value" "SC10U6D3V3MX-GP"
			(at 0 -2.8194 90)
			(unlocked yes)
			(layer "F.Fab")
			(hide yes)
			(effects
				(font
					(size 1.016 1.016)
					(thickness 0.1524)
				)
			)
		)
		(property "Device Type" "C603H38"
			(at 0 -4.3434 90)
			(unlocked yes)
			(layer "F.Fab")
			(hide yes)
			(effects
				(font
					(size 1.016 1.016)
					(thickness 0.1524)
				)
			)
		)
		(duplicate_pad_numbers_are_jumpers no)
		(fp_line
			(start -0.4064 0)
			(end 0.4064 0)
			(stroke
				(width 0.2286)
				(type default)
			)
			(layer "F.SilkS")
		)
		(fp_rect
			(start -0.635 1.1811)
			(end 0.635 -1.1811)
			(stroke
				(width 0)
				(type default)
			)
			(fill no)
			(layer "F.CrtYd")
		)
		(fp_rect
			(start -0.635 1.1811)
			(end 0.635 -1.1811)
			(stroke
				(width 0)
				(type default)
			)
			(fill no)
			(layer "F.Fab")
		)
		(pad "1" smd custom
			(at 0 -0.6604 90)
			(size 0.19685 0.19685)
			(layers "F.Cu" "F.Mask" "F.Paste")
			(net "PV_VTT_DDR_B")
			(options
				(clearance outline)
				(anchor circle)
			)
			(primitives
				(gr_poly
					(pts
						(arc
							(start 0.508 -0.2921)
							(mid 0.478242 -0.363942)
							(end 0.4064 -0.3937)
						)
						(arc
							(start -0.4064 -0.3937)
							(mid -0.478242 -0.363942)
							(end -0.508 -0.2921)
						)
						(arc
							(start -0.508 0.2921)
							(mid -0.478242 0.363942)
							(end -0.4064 0.3937)
						)
						(arc
							(start 0.4064 0.3937)
							(mid 0.478242 0.363942)
							(end 0.508 0.2921)
						)
					)
					(width 0)
					(fill yes)
				)
			)
		)
		(pad "2" smd custom
			(at 0 0.6604 90)
			(size 0.19685 0.19685)
			(layers "F.Cu" "F.Mask" "F.Paste")
			(net "GND")
			(options
				(clearance outline)
				(anchor circle)
			)
			(primitives
				(gr_poly
					(pts
						(arc
							(start 0.508 -0.2921)
							(mid 0.478242 -0.363942)
							(end 0.4064 -0.3937)
						)
						(arc
							(start -0.4064 -0.3937)
							(mid -0.478242 -0.363942)
							(end -0.508 -0.2921)
						)
						(arc
							(start -0.508 0.2921)
							(mid -0.478242 0.363942)
							(end -0.4064 0.3937)
						)
						(arc
							(start 0.4064 0.3937)
							(mid 0.478242 0.363942)
							(end 0.508 0.2921)
						)
					)
					(width 0)
					(fill yes)
				)
			)
		)
	)
	(footprint ""
		(layer "F.Cu")
		(at 132.842 -19.431 180)
		(property "Reference" "R506"
			(at 0 0 180)
			(layer "F.SilkS")
			(hide yes)
			(effects
				(font
					(size 1.27 1.27)
				)
			)
		)
		(property "Value" "1KR2F-3-GP"
			(at 1.7907 -1.1176 180)
			(unlocked yes)
			(layer "F.Fab")
			(hide yes)
			(effects
				(font
					(size 1.016 1.016)
					(thickness 0.1524)
				)
			)
		)
		(property "Device Type" "R402H16"
			(at 1.7907 -2.6416 180)
			(unlocked yes)
			(layer "F.Fab")
			(hide yes)
			(effects
				(font
					(size 1.016 1.016)
					(thickness 0.1524)
				)
			)
		)
		(duplicate_pad_numbers_are_jumpers no)
		(fp_rect
			(start -0.381 0.8382)
			(end 0.381 -0.8382)
			(stroke
				(width 0)
				(type default)
			)
			(fill no)
			(layer "F.CrtYd")
		)
		(fp_rect
			(start -0.381 0.8382)
			(end 0.381 -0.8382)
			(stroke
				(width 0)
				(type default)
			)
			(fill no)
			(layer "F.Fab")
		)
		(pad "1" smd custom
			(at 0 -0.4318 180)
			(size 0.127 0.127)
			(layers "F.Cu" "F.Mask" "F.Paste")
			(net "POWER_GOOD_R")
			(options
				(clearance outline)
				(anchor circle)
			)
			(primitives
				(gr_poly
					(pts
						(arc
							(start -0.2032 -0.2794)
							(mid -0.239121 -0.264521)
							(end -0.254 -0.2286)
						)
						(arc
							(start -0.254 0.2286)
							(mid -0.239121 0.264521)
							(end -0.2032 0.2794)
						)
						(arc
							(start 0.2032 0.2794)
							(mid 0.239121 0.264521)
							(end 0.254 0.2286)
						)
						(arc
							(start 0.254 -0.2286)
							(mid 0.239121 -0.264521)
							(end 0.2032 -0.2794)
						)
					)
					(width 0)
					(fill yes)
				)
			)
		)
		(pad "2" smd custom
			(at 0 0.4318 180)
			(size 0.127 0.127)
			(layers "F.Cu" "F.Mask" "F.Paste")
			(net "GND")
			(options
				(clearance outline)
				(anchor circle)
			)
			(primitives
				(gr_poly
					(pts
						(arc
							(start -0.2032 -0.2794)
							(mid -0.239121 -0.264521)
							(end -0.254 -0.2286)
						)
						(arc
							(start -0.254 0.2286)
							(mid -0.239121 0.264521)
							(end -0.2032 0.2794)
						)
						(arc
							(start 0.2032 0.2794)
							(mid 0.239121 0.264521)
							(end 0.254 0.2286)
						)
						(arc
							(start 0.254 -0.2286)
							(mid 0.239121 -0.264521)
							(end 0.2032 -0.2794)
						)
					)
					(width 0)
					(fill yes)
				)
			)
		)
	)
	(footprint ""
		(layer "F.Cu")
		(at 38.862 -42.037)
		(property "Reference" "R59"
			(at 0 0 0)
			(layer "F.SilkS")
			(hide yes)
			(effects
				(font
					(size 1.27 1.27)
				)
			)
		)
		(property "Value" "33R2F-3-GP"
			(at 1.7907 -1.1176 0)
			(unlocked yes)
			(layer "F.Fab")
			(hide yes)
			(effects
				(font
					(size 1.016 1.016)
					(thickness 0.1524)
				)
			)
		)
		(property "Device Type" "R402H16"
			(at 1.7907 -2.6416 0)
			(unlocked yes)
			(layer "F.Fab")
			(hide yes)
			(effects
				(font
					(size 1.016 1.016)
					(thickness 0.1524)
				)
			)
		)
		(duplicate_pad_numbers_are_jumpers no)
		(fp_rect
			(start -0.381 0.8382)
			(end 0.381 -0.8382)
			(stroke
				(width 0)
				(type default)
			)
			(fill no)
			(layer "F.CrtYd")
		)
		(fp_rect
			(start -0.381 0.8382)
			(end 0.381 -0.8382)
			(stroke
				(width 0)
				(type default)
			)
			(fill no)
			(layer "F.Fab")
		)
		(pad "1" smd custom
			(at 0 -0.4318)
			(size 0.127 0.127)
			(layers "F.Cu" "F.Mask" "F.Paste")
			(net "P3V3_CPU_PG_S2")
			(options
				(clearance outline)
				(anchor circle)
			)
			(primitives
				(gr_poly
					(pts
						(arc
							(start -0.2032 -0.2794)
							(mid -0.239121 -0.264521)
							(end -0.254 -0.2286)
						)
						(arc
							(start -0.254 0.2286)
							(mid -0.239121 0.264521)
							(end -0.2032 0.2794)
						)
						(arc
							(start 0.2032 0.2794)
							(mid 0.239121 0.264521)
							(end 0.254 0.2286)
						)
						(arc
							(start 0.254 -0.2286)
							(mid 0.239121 -0.264521)
							(end 0.2032 -0.2794)
						)
					)
					(width 0)
					(fill yes)
				)
			)
		)
		(pad "2" smd custom
			(at 0 0.4318)
			(size 0.127 0.127)
			(layers "F.Cu" "F.Mask" "F.Paste")
			(net "CPU_RSMRST#")
			(options
				(clearance outline)
				(anchor circle)
			)
			(primitives
				(gr_poly
					(pts
						(arc
							(start -0.2032 -0.2794)
							(mid -0.239121 -0.264521)
							(end -0.254 -0.2286)
						)
						(arc
							(start -0.254 0.2286)
							(mid -0.239121 0.264521)
							(end -0.2032 0.2794)
						)
						(arc
							(start 0.2032 0.2794)
							(mid 0.239121 0.264521)
							(end 0.254 0.2286)
						)
						(arc
							(start 0.254 -0.2286)
							(mid 0.239121 -0.264521)
							(end 0.2032 -0.2794)
						)
					)
					(width 0)
					(fill yes)
				)
			)
		)
	)
	(footprint ""
		(layer "F.Cu")
		(at 129.3368 -25.781 180)
		(property "Reference" "R483"
			(at 0 0 180)
			(layer "F.SilkS")
			(hide yes)
			(effects
				(font
					(size 1.27 1.27)
				)
			)
		)
		(property "Value" "0R2J-2-GP"
			(at 1.7907 -1.1176 180)
			(unlocked yes)
			(layer "F.Fab")
			(hide yes)
			(effects
				(font
					(size 1.016 1.016)
					(thickness 0.1524)
				)
			)
		)
		(property "Device Type" "R402H16"
			(at 1.7907 -2.6416 180)
			(unlocked yes)
			(layer "F.Fab")
			(hide yes)
			(effects
				(font
					(size 1.016 1.016)
					(thickness 0.1524)
				)
			)
		)
		(duplicate_pad_numbers_are_jumpers no)
		(fp_rect
			(start -0.381 0.8382)
			(end 0.381 -0.8382)
			(stroke
				(width 0)
				(type default)
			)
			(fill no)
			(layer "F.CrtYd")
		)
		(fp_rect
			(start -0.381 0.8382)
			(end 0.381 -0.8382)
			(stroke
				(width 0)
				(type default)
			)
			(fill no)
			(layer "F.Fab")
		)
		(pad "1" smd custom
			(at 0 -0.4318 180)
			(size 0.127 0.127)
			(layers "F.Cu" "F.Mask" "F.Paste")
			(net "PMU_PLTRST#")
			(options
				(clearance outline)
				(anchor circle)
			)
			(primitives
				(gr_poly
					(pts
						(arc
							(start -0.2032 -0.2794)
							(mid -0.239121 -0.264521)
							(end -0.254 -0.2286)
						)
						(arc
							(start -0.254 0.2286)
							(mid -0.239121 0.264521)
							(end -0.2032 0.2794)
						)
						(arc
							(start 0.2032 0.2794)
							(mid 0.239121 0.264521)
							(end 0.254 0.2286)
						)
						(arc
							(start 0.254 -0.2286)
							(mid 0.239121 -0.264521)
							(end 0.2032 -0.2794)
						)
					)
					(width 0)
					(fill yes)
				)
			)
		)
		(pad "2" smd custom
			(at 0 0.4318 180)
			(size 0.127 0.127)
			(layers "F.Cu" "F.Mask" "F.Paste")
			(net "PMU_PLD_R_PLTRST#")
			(options
				(clearance outline)
				(anchor circle)
			)
			(primitives
				(gr_poly
					(pts
						(arc
							(start -0.2032 -0.2794)
							(mid -0.239121 -0.264521)
							(end -0.254 -0.2286)
						)
						(arc
							(start -0.254 0.2286)
							(mid -0.239121 0.264521)
							(end -0.2032 0.2794)
						)
						(arc
							(start 0.2032 0.2794)
							(mid 0.239121 0.264521)
							(end 0.254 0.2286)
						)
						(arc
							(start 0.254 -0.2286)
							(mid 0.239121 -0.264521)
							(end 0.2032 -0.2794)
						)
					)
					(width 0)
					(fill yes)
				)
			)
		)
	)
	(footprint ""
		(layer "F.Cu")
		(at 27.0764 -56.9468 90)
		(property "Reference" "PR54"
			(at 0 0 90)
			(layer "F.SilkS")
			(hide yes)
			(effects
				(font
					(size 1.27 1.27)
				)
			)
		)
		(property "Value" "0R3J-0-U-GP"
			(at -0.0254 -2.0193 90)
			(unlocked yes)
			(layer "F.Fab")
			(hide yes)
			(effects
				(font
					(size 1.016 1.016)
					(thickness 0.1524)
				)
			)
		)
		(property "Device Type" "R603H22"
			(at -0.0254 -3.5433 90)
			(unlocked yes)
			(layer "F.Fab")
			(hide yes)
			(effects
				(font
					(size 1.016 1.016)
					(thickness 0.1524)
				)
			)
		)
		(duplicate_pad_numbers_are_jumpers no)
		(fp_line
			(start 0.4318 0)
			(end 0.2032 0)
			(stroke
				(width 0.2032)
				(type default)
			)
			(layer "F.SilkS")
		)
		(fp_line
			(start -0.2032 0)
			(end -0.4191 0)
			(stroke
				(width 0.2032)
				(type default)
			)
			(layer "F.SilkS")
		)
		(fp_rect
			(start -0.635 1.1811)
			(end 0.635 -1.1811)
			(stroke
				(width 0)
				(type default)
			)
			(fill no)
			(layer "F.CrtYd")
		)
		(fp_rect
			(start -0.635 1.1811)
			(end 0.635 -1.1811)
			(stroke
				(width 0)
				(type default)
			)
			(fill no)
			(layer "F.Fab")
		)
		(pad "1" smd custom
			(at 0 -0.6604 90)
			(size 0.19685 0.19685)
			(layers "F.Cu" "F.Mask" "F.Paste")
			(net "VR_PVCCP_GL")
			(options
				(clearance outline)
				(anchor circle)
			)
			(primitives
				(gr_poly
					(pts
						(arc
							(start 0.508 -0.2921)
							(mid 0.478242 -0.363942)
							(end 0.4064 -0.3937)
						)
						(arc
							(start -0.4064 -0.3937)
							(mid -0.478242 -0.363942)
							(end -0.508 -0.2921)
						)
						(arc
							(start -0.508 0.2921)
							(mid -0.478242 0.363942)
							(end -0.4064 0.3937)
						)
						(arc
							(start 0.4064 0.3937)
							(mid 0.478242 0.363942)
							(end 0.508 0.2921)
						)
					)
					(width 0)
					(fill yes)
				)
			)
		)
		(pad "2" smd custom
			(at 0 0.6604 90)
			(size 0.19685 0.19685)
			(layers "F.Cu" "F.Mask" "F.Paste")
			(net "VR_PVCCP_LH_R")
			(options
				(clearance outline)
				(anchor circle)
			)
			(primitives
				(gr_poly
					(pts
						(arc
							(start 0.508 -0.2921)
							(mid 0.478242 -0.363942)
							(end 0.4064 -0.3937)
						)
						(arc
							(start -0.4064 -0.3937)
							(mid -0.478242 -0.363942)
							(end -0.508 -0.2921)
						)
						(arc
							(start -0.508 0.2921)
							(mid -0.478242 0.363942)
							(end -0.4064 0.3937)
						)
						(arc
							(start 0.4064 0.3937)
							(mid 0.478242 0.363942)
							(end 0.508 0.2921)
						)
					)
					(width 0)
					(fill yes)
				)
			)
		)
	)
	(footprint ""
		(layer "F.Cu")
		(at 168.4528 -52.07 -90)
		(property "Reference" "R182"
			(at 0 0 270)
			(layer "F.SilkS")
			(hide yes)
			(effects
				(font
					(size 1.27 1.27)
				)
			)
		)
		(property "Value" "33R2F-3-GP"
			(at 1.7907 -1.1176 270)
			(unlocked yes)
			(layer "F.Fab")
			(hide yes)
			(effects
				(font
					(size 1.016 1.016)
					(thickness 0.1524)
				)
			)
		)
		(property "Device Type" "R402H16"
			(at 1.7907 -2.6416 270)
			(unlocked yes)
			(layer "F.Fab")
			(hide yes)
			(effects
				(font
					(size 1.016 1.016)
					(thickness 0.1524)
				)
			)
		)
		(duplicate_pad_numbers_are_jumpers no)
		(fp_rect
			(start -0.381 0.8382)
			(end 0.381 -0.8382)
			(stroke
				(width 0)
				(type default)
			)
			(fill no)
			(layer "F.CrtYd")
		)
		(fp_rect
			(start -0.381 0.8382)
			(end 0.381 -0.8382)
			(stroke
				(width 0)
				(type default)
			)
			(fill no)
			(layer "F.Fab")
		)
		(pad "1" smd custom
			(at 0 -0.4318 270)
			(size 0.127 0.127)
			(layers "F.Cu" "F.Mask" "F.Paste")
			(net "C_CSO#")
			(options
				(clearance outline)
				(anchor circle)
			)
			(primitives
				(gr_poly
					(pts
						(arc
							(start -0.2032 -0.2794)
							(mid -0.239121 -0.264521)
							(end -0.254 -0.2286)
						)
						(arc
							(start -0.254 0.2286)
							(mid -0.239121 0.264521)
							(end -0.2032 0.2794)
						)
						(arc
							(start 0.2032 0.2794)
							(mid 0.239121 0.264521)
							(end 0.254 0.2286)
						)
						(arc
							(start 0.254 -0.2286)
							(mid 0.239121 -0.264521)
							(end 0.2032 -0.2794)
						)
					)
					(width 0)
					(fill yes)
				)
			)
		)
		(pad "2" smd custom
			(at 0 0.4318 270)
			(size 0.127 0.127)
			(layers "F.Cu" "F.Mask" "F.Paste")
			(net "C_R_CSO#")
			(options
				(clearance outline)
				(anchor circle)
			)
			(primitives
				(gr_poly
					(pts
						(arc
							(start -0.2032 -0.2794)
							(mid -0.239121 -0.264521)
							(end -0.254 -0.2286)
						)
						(arc
							(start -0.254 0.2286)
							(mid -0.239121 0.264521)
							(end -0.2032 0.2794)
						)
						(arc
							(start 0.2032 0.2794)
							(mid 0.239121 0.264521)
							(end 0.254 0.2286)
						)
						(arc
							(start 0.254 -0.2286)
							(mid 0.239121 -0.264521)
							(end 0.2032 -0.2794)
						)
					)
					(width 0)
					(fill yes)
				)
			)
		)
	)
	(footprint ""
		(layer "F.Cu")
		(at 169.926 -40.132 -90)
		(property "Reference" "PR227"
			(at 0 0 270)
			(layer "F.SilkS")
			(hide yes)
			(effects
				(font
					(size 1.27 1.27)
				)
			)
		)
		(property "Value" "31K6R2F-GP"
			(at 1.7907 -1.1176 270)
			(unlocked yes)
			(layer "F.Fab")
			(hide yes)
			(effects
				(font
					(size 1.016 1.016)
					(thickness 0.1524)
				)
			)
		)
		(property "Device Type" "R402H16"
			(at 1.7907 -2.6416 270)
			(unlocked yes)
			(layer "F.Fab")
			(hide yes)
			(effects
				(font
					(size 1.016 1.016)
					(thickness 0.1524)
				)
			)
		)
		(duplicate_pad_numbers_are_jumpers no)
		(fp_rect
			(start -0.381 0.8382)
			(end 0.381 -0.8382)
			(stroke
				(width 0)
				(type default)
			)
			(fill no)
			(layer "F.CrtYd")
		)
		(fp_rect
			(start -0.381 0.8382)
			(end 0.381 -0.8382)
			(stroke
				(width 0)
				(type default)
			)
			(fill no)
			(layer "F.Fab")
		)
		(pad "1" smd custom
			(at 0 -0.4318 270)
			(size 0.127 0.127)
			(layers "F.Cu" "F.Mask" "F.Paste")
			(net "P2V5_STBY_OUT")
			(options
				(clearance outline)
				(anchor circle)
			)
			(primitives
				(gr_poly
					(pts
						(arc
							(start -0.2032 -0.2794)
							(mid -0.239121 -0.264521)
							(end -0.254 -0.2286)
						)
						(arc
							(start -0.254 0.2286)
							(mid -0.239121 0.264521)
							(end -0.2032 0.2794)
						)
						(arc
							(start 0.2032 0.2794)
							(mid 0.239121 0.264521)
							(end 0.254 0.2286)
						)
						(arc
							(start 0.254 -0.2286)
							(mid 0.239121 -0.264521)
							(end 0.2032 -0.2794)
						)
					)
					(width 0)
					(fill yes)
				)
			)
		)
		(pad "2" smd custom
			(at 0 0.4318 270)
			(size 0.127 0.127)
			(layers "F.Cu" "F.Mask" "F.Paste")
			(net "P2V5_STBY_FB")
			(options
				(clearance outline)
				(anchor circle)
			)
			(primitives
				(gr_poly
					(pts
						(arc
							(start -0.2032 -0.2794)
							(mid -0.239121 -0.264521)
							(end -0.254 -0.2286)
						)
						(arc
							(start -0.254 0.2286)
							(mid -0.239121 0.264521)
							(end -0.2032 0.2794)
						)
						(arc
							(start 0.2032 0.2794)
							(mid 0.239121 0.264521)
							(end 0.254 0.2286)
						)
						(arc
							(start 0.254 -0.2286)
							(mid 0.239121 -0.264521)
							(end 0.2032 -0.2794)
						)
					)
					(width 0)
					(fill yes)
				)
			)
		)
	)
)
